(kicad_pcb
	(version 20260206)
	(generator "pcbnew")
	(generator_version "10.0")
	(general
		(thickness 1.6)
		(legacy_teardrops no)
	)
	(paper "A4")
	(title_block
		(title "04192023_DAF0TMB3IC0_F0TG_MB_C_brd_V02_OCP.brd")
		(comment 1 "Grand Teton / footprints 7568-7573 of 8354")
	)
	(layers
		(0 "F.Cu" signal "TOP")
		(4 "In1.Cu" signal "GND")
		(6 "In2.Cu" signal "IN1")
		(8 "In3.Cu" signal "GND1")
		(10 "In4.Cu" signal "IN2")
		(12 "In5.Cu" signal "GND2")
		(14 "In6.Cu" signal "IN3")
		(16 "In7.Cu" signal "GND3")
		(18 "In8.Cu" signal "VCC")
		(20 "In9.Cu" signal "VCC1")
		(22 "In10.Cu" signal "GND4")
		(24 "In11.Cu" signal "IN4")
		(26 "In12.Cu" signal "GND5")
		(28 "In13.Cu" signal "IN5")
		(30 "In14.Cu" signal "GND6")
		(32 "In15.Cu" signal "IN6")
		(34 "In16.Cu" signal "GND7")
		(2 "B.Cu" signal "BOTTOM")
		(9 "F.Adhes" user "F.Adhesive")
		(11 "B.Adhes" user "B.Adhesive")
		(13 "F.Paste" user "Package Geometry/Pastemask Top")
		(15 "B.Paste" user "Package Geometry/Pastemask Bottom")
		(5 "F.SilkS" user "Ref Des/Silkscreen Top")
		(7 "B.SilkS" user "Ref Des/Silkscreen Bottom")
		(1 "F.Mask" user "Board Geometry/Soldermask Top")
		(3 "B.Mask" user "Board Geometry/Soldermask Bottom")
		(17 "Dwgs.User" user "User.Drawings")
		(19 "Cmts.User" user "User.Comments")
		(21 "Eco1.User" user "User.Eco1")
		(23 "Eco2.User" user "User.Eco2")
		(25 "Edge.Cuts" user "Board Geometry/Outline")
		(27 "Margin" user)
		(31 "F.CrtYd" user "Package Geometry/Place Bound Top")
		(29 "B.CrtYd" user "Package Geometry/Place Bound Bottom")
		(35 "F.Fab" user "Ref Des/Assembly Top")
		(33 "B.Fab" user "Ref Des/Assembly Bottom")
	)
	(footprint ""
		(layer "B.Cu")
		(at 167.502332 -434.882544 180)
		(property "Reference" "Q132"
			(at -5.782056 0.352552 0)
			(unlocked yes)
			(layer "B.SilkS")
			(effects
				(font
					(size 0.7874 0.5842)
					(thickness 0.1524)
				)
				(justify left mirror)
			)
		)
		(property "Value" ""
			(at 0 0 0)
			(layer "B.Fab")
			(effects
				(font
					(size 1.27 1.27)
				)
				(justify mirror)
			)
		)
		(duplicate_pad_numbers_are_jumpers no)
		(fp_line
			(start 1.332738 1.100074)
			(end 1.332738 -1.100074)
			(stroke
				(width 0.1524)
				(type default)
			)
			(layer "B.SilkS")
		)
		(fp_line
			(start 1.332738 -1.100074)
			(end 0.4826 -1.100074)
			(stroke
				(width 0.1524)
				(type default)
			)
			(layer "B.SilkS")
		)
		(fp_line
			(start 0.4826 -1.100074)
			(end 0 -0.541274)
			(stroke
				(width 0.1524)
				(type default)
			)
			(layer "B.SilkS")
		)
		(fp_line
			(start 0 -0.541274)
			(end -0.4826 -1.100074)
			(stroke
				(width 0.1524)
				(type default)
			)
			(layer "B.SilkS")
		)
		(fp_line
			(start -0.4826 -1.100074)
			(end -1.332738 -1.100074)
			(stroke
				(width 0.1524)
				(type default)
			)
			(layer "B.SilkS")
		)
		(fp_line
			(start -1.332738 1.100074)
			(end 1.332738 1.100074)
			(stroke
				(width 0.1524)
				(type default)
			)
			(layer "B.SilkS")
		)
		(fp_line
			(start -1.332738 -1.100074)
			(end -1.332738 1.100074)
			(stroke
				(width 0.1524)
				(type default)
			)
			(layer "B.SilkS")
		)
		(fp_poly
			(pts
				(xy 1.020064 -1.309624) (xy 1.371092 -2.011426) (xy 0.669036 -2.011426)
			)
			(stroke
				(width 0)
				(type default)
			)
			(fill yes)
			(layer "B.SilkS")
		)
		(fp_line
			(start 0.674878 1.100074)
			(end 0.674878 -1.100074)
			(stroke
				(width 0.1)
				(type default)
			)
			(layer "B.Fab")
		)
		(fp_line
			(start 0.674878 -1.100074)
			(end -0.674878 -1.100074)
			(stroke
				(width 0.1)
				(type default)
			)
			(layer "B.Fab")
		)
		(fp_line
			(start -0.674878 1.100074)
			(end 0.674878 1.100074)
			(stroke
				(width 0.1)
				(type default)
			)
			(layer "B.Fab")
		)
		(fp_line
			(start -0.674878 -1.100074)
			(end -0.674878 1.100074)
			(stroke
				(width 0.1)
				(type default)
			)
			(layer "B.Fab")
		)
		(fp_poly
			(pts
				(xy 2.2352 -0.298958) (xy 2.2352 -1.001014) (xy 1.533144 -0.649986)
			)
			(stroke
				(width 0)
				(type default)
			)
			(fill yes)
			(layer "B.Fab")
		)
		(pad "1" smd rect
			(at 0.94996 -0.649986 270)
			(size 0.4318 0.508)
			(layers "B.Cu" "B.Mask" "B.Paste")
			(net "GND")
		)
		(pad "2" smd rect
			(at 0.94996 0 270)
			(size 0.4318 0.508)
			(layers "B.Cu" "B.Mask" "B.Paste")
			(net "PRSNT_CABLE_GPU_B3_N")
		)
		(pad "3" smd rect
			(at 0.94996 0.649986 270)
			(size 0.4318 0.508)
			(layers "B.Cu" "B.Mask" "B.Paste")
			(net "PRSNT_CABLE_GPU_B3_ISO_N")
		)
		(pad "4" smd rect
			(at -0.94996 0.649986 270)
			(size 0.4318 0.508)
			(layers "B.Cu" "B.Mask" "B.Paste")
			(net "GND")
		)
		(pad "5" smd rect
			(at -0.94996 0 270)
			(size 0.4318 0.508)
			(layers "B.Cu" "B.Mask" "B.Paste")
			(net "PRSNT_CABLE_GPU_B3")
		)
		(pad "6" smd rect
			(at -0.94996 -0.649986 270)
			(size 0.4318 0.508)
			(layers "B.Cu" "B.Mask" "B.Paste")
			(net "PRSNT_CABLE_GPU_B3")
		)
	)
	(footprint ""
		(layer "B.Cu")
		(at 25.92324 -193.996564)
		(property "Reference" "R107"
			(at 0 0 0)
			(layer "B.SilkS")
			(hide yes)
			(effects
				(font
					(size 1.27 1.27)
				)
				(justify mirror)
			)
		)
		(property "Value" ""
			(at 0 0 0)
			(layer "B.Fab")
			(effects
				(font
					(size 1.27 1.27)
				)
				(justify mirror)
			)
		)
		(duplicate_pad_numbers_are_jumpers no)
		(fp_line
			(start -0.7874 -0.4064)
			(end -0.7874 0.4064)
			(stroke
				(width 0.1524)
				(type default)
			)
			(layer "B.SilkS")
		)
		(fp_line
			(start -0.7874 0.4064)
			(end 0.7874 0.4064)
			(stroke
				(width 0.1524)
				(type default)
			)
			(layer "B.SilkS")
		)
		(fp_line
			(start 0.7874 -0.4064)
			(end -0.7874 -0.4064)
			(stroke
				(width 0.1524)
				(type default)
			)
			(layer "B.SilkS")
		)
		(fp_line
			(start 0.7874 0.4064)
			(end 0.7874 -0.4064)
			(stroke
				(width 0.1524)
				(type default)
			)
			(layer "B.SilkS")
		)
		(fp_line
			(start -0.67945 -0.3048)
			(end -0.67945 0.3048)
			(stroke
				(width 0.1)
				(type default)
			)
			(layer "B.Fab")
		)
		(fp_line
			(start -0.67945 0.3048)
			(end -0.120396 0.3048)
			(stroke
				(width 0.1)
				(type default)
			)
			(layer "B.Fab")
		)
		(fp_line
			(start -0.12065 -0.3048)
			(end -0.67945 -0.3048)
			(stroke
				(width 0.1)
				(type default)
			)
			(layer "B.Fab")
		)
		(fp_line
			(start -0.12065 -0.2794)
			(end -0.12065 -0.3048)
			(stroke
				(width 0.1)
				(type default)
			)
			(layer "B.Fab")
		)
		(fp_line
			(start -0.120396 0.2794)
			(end 0.12065 0.2794)
			(stroke
				(width 0.1)
				(type default)
			)
			(layer "B.Fab")
		)
		(fp_line
			(start -0.120396 0.3048)
			(end -0.120396 0.2794)
			(stroke
				(width 0.1)
				(type default)
			)
			(layer "B.Fab")
		)
		(fp_line
			(start 0.12065 -0.305054)
			(end 0.12065 -0.2794)
			(stroke
				(width 0.1)
				(type default)
			)
			(layer "B.Fab")
		)
		(fp_line
			(start 0.12065 -0.2794)
			(end -0.12065 -0.2794)
			(stroke
				(width 0.1)
				(type default)
			)
			(layer "B.Fab")
		)
		(fp_line
			(start 0.12065 0.2794)
			(end 0.12065 0.3048)
			(stroke
				(width 0.1)
				(type default)
			)
			(layer "B.Fab")
		)
		(fp_line
			(start 0.12065 0.3048)
			(end 0.67945 0.3048)
			(stroke
				(width 0.1)
				(type default)
			)
			(layer "B.Fab")
		)
		(fp_line
			(start 0.67945 -0.305054)
			(end 0.12065 -0.305054)
			(stroke
				(width 0.1)
				(type default)
			)
			(layer "B.Fab")
		)
		(fp_line
			(start 0.67945 0.3048)
			(end 0.67945 -0.305054)
			(stroke
				(width 0.1)
				(type default)
			)
			(layer "B.Fab")
		)
		(pad "1" smd circle
			(at 0.40005 0 180)
			(size 0 0)
			(layers "B.Cu" "B.Mask" "B.Paste")
			(net "P3V3")
		)
		(pad "2" smd circle
			(at -0.40005 0 180)
			(size 0 0)
			(layers "B.Cu" "B.Mask" "B.Paste")
			(net "PWRGD_CHE_CPU1_DIMM")
		)
	)
	(footprint ""
		(layer "B.Cu")
		(at 24.765 -361.061 180)
		(property "Reference" "R8243"
			(at 0 0 0)
			(layer "B.SilkS")
			(hide yes)
			(effects
				(font
					(size 1.27 1.27)
				)
				(justify mirror)
			)
		)
		(property "Value" ""
			(at 0 0 0)
			(layer "B.Fab")
			(effects
				(font
					(size 1.27 1.27)
				)
				(justify mirror)
			)
		)
		(duplicate_pad_numbers_are_jumpers no)
		(fp_line
			(start 0.7874 0.4064)
			(end 0.7874 -0.4064)
			(stroke
				(width 0.1524)
				(type default)
			)
			(layer "B.SilkS")
		)
		(fp_line
			(start 0.7874 -0.4064)
			(end -0.7874 -0.4064)
			(stroke
				(width 0.1524)
				(type default)
			)
			(layer "B.SilkS")
		)
		(fp_line
			(start -0.7874 0.4064)
			(end 0.7874 0.4064)
			(stroke
				(width 0.1524)
				(type default)
			)
			(layer "B.SilkS")
		)
		(fp_line
			(start -0.7874 -0.4064)
			(end -0.7874 0.4064)
			(stroke
				(width 0.1524)
				(type default)
			)
			(layer "B.SilkS")
		)
		(fp_line
			(start 0.67945 0.3048)
			(end 0.67945 -0.305054)
			(stroke
				(width 0.1)
				(type default)
			)
			(layer "B.Fab")
		)
		(fp_line
			(start 0.67945 -0.305054)
			(end 0.12065 -0.305054)
			(stroke
				(width 0.1)
				(type default)
			)
			(layer "B.Fab")
		)
		(fp_line
			(start 0.12065 0.3048)
			(end 0.67945 0.3048)
			(stroke
				(width 0.1)
				(type default)
			)
			(layer "B.Fab")
		)
		(fp_line
			(start 0.12065 0.2794)
			(end 0.12065 0.3048)
			(stroke
				(width 0.1)
				(type default)
			)
			(layer "B.Fab")
		)
		(fp_line
			(start 0.12065 -0.2794)
			(end -0.12065 -0.2794)
			(stroke
				(width 0.1)
				(type default)
			)
			(layer "B.Fab")
		)
		(fp_line
			(start 0.12065 -0.305054)
			(end 0.12065 -0.2794)
			(stroke
				(width 0.1)
				(type default)
			)
			(layer "B.Fab")
		)
		(fp_line
			(start -0.120396 0.3048)
			(end -0.120396 0.2794)
			(stroke
				(width 0.1)
				(type default)
			)
			(layer "B.Fab")
		)
		(fp_line
			(start -0.120396 0.2794)
			(end 0.12065 0.2794)
			(stroke
				(width 0.1)
				(type default)
			)
			(layer "B.Fab")
		)
		(fp_line
			(start -0.12065 -0.2794)
			(end -0.12065 -0.3048)
			(stroke
				(width 0.1)
				(type default)
			)
			(layer "B.Fab")
		)
		(fp_line
			(start -0.12065 -0.3048)
			(end -0.67945 -0.3048)
			(stroke
				(width 0.1)
				(type default)
			)
			(layer "B.Fab")
		)
		(fp_line
			(start -0.67945 0.3048)
			(end -0.120396 0.3048)
			(stroke
				(width 0.1)
				(type default)
			)
			(layer "B.Fab")
		)
		(fp_line
			(start -0.67945 -0.3048)
			(end -0.67945 0.3048)
			(stroke
				(width 0.1)
				(type default)
			)
			(layer "B.Fab")
		)
		(pad "1" smd circle
			(at 0.40005 0)
			(size 0 0)
			(layers "B.Cu" "B.Mask" "B.Paste")
			(net "PWRGD_PVDDIO_P1")
		)
		(pad "2" smd circle
			(at -0.40005 0)
			(size 0 0)
			(layers "B.Cu" "B.Mask" "B.Paste")
			(net "PWRGD_PVDDIO_P1_R")
		)
	)
	(footprint ""
		(layer "B.Cu")
		(at 428.98695 -38.039548 180)
		(property "Reference" "R6043"
			(at 0 0 0)
			(layer "B.SilkS")
			(hide yes)
			(effects
				(font
					(size 1.27 1.27)
				)
				(justify mirror)
			)
		)
		(property "Value" ""
			(at 0 0 0)
			(layer "B.Fab")
			(effects
				(font
					(size 1.27 1.27)
				)
				(justify mirror)
			)
		)
		(duplicate_pad_numbers_are_jumpers no)
		(fp_line
			(start 0.7874 0.4064)
			(end 0.7874 -0.4064)
			(stroke
				(width 0.1524)
				(type default)
			)
			(layer "B.SilkS")
		)
		(fp_line
			(start 0.7874 -0.4064)
			(end -0.7874 -0.4064)
			(stroke
				(width 0.1524)
				(type default)
			)
			(layer "B.SilkS")
		)
		(fp_line
			(start -0.7874 0.4064)
			(end 0.7874 0.4064)
			(stroke
				(width 0.1524)
				(type default)
			)
			(layer "B.SilkS")
		)
		(fp_line
			(start -0.7874 -0.4064)
			(end -0.7874 0.4064)
			(stroke
				(width 0.1524)
				(type default)
			)
			(layer "B.SilkS")
		)
		(fp_line
			(start 0.67945 0.3048)
			(end 0.67945 -0.305054)
			(stroke
				(width 0.1)
				(type default)
			)
			(layer "B.Fab")
		)
		(fp_line
			(start 0.67945 -0.305054)
			(end 0.12065 -0.305054)
			(stroke
				(width 0.1)
				(type default)
			)
			(layer "B.Fab")
		)
		(fp_line
			(start 0.12065 0.3048)
			(end 0.67945 0.3048)
			(stroke
				(width 0.1)
				(type default)
			)
			(layer "B.Fab")
		)
		(fp_line
			(start 0.12065 0.2794)
			(end 0.12065 0.3048)
			(stroke
				(width 0.1)
				(type default)
			)
			(layer "B.Fab")
		)
		(fp_line
			(start 0.12065 -0.2794)
			(end -0.12065 -0.2794)
			(stroke
				(width 0.1)
				(type default)
			)
			(layer "B.Fab")
		)
		(fp_line
			(start 0.12065 -0.305054)
			(end 0.12065 -0.2794)
			(stroke
				(width 0.1)
				(type default)
			)
			(layer "B.Fab")
		)
		(fp_line
			(start -0.120396 0.3048)
			(end -0.120396 0.2794)
			(stroke
				(width 0.1)
				(type default)
			)
			(layer "B.Fab")
		)
		(fp_line
			(start -0.120396 0.2794)
			(end 0.12065 0.2794)
			(stroke
				(width 0.1)
				(type default)
			)
			(layer "B.Fab")
		)
		(fp_line
			(start -0.12065 -0.2794)
			(end -0.12065 -0.3048)
			(stroke
				(width 0.1)
				(type default)
			)
			(layer "B.Fab")
		)
		(fp_line
			(start -0.12065 -0.3048)
			(end -0.67945 -0.3048)
			(stroke
				(width 0.1)
				(type default)
			)
			(layer "B.Fab")
		)
		(fp_line
			(start -0.67945 0.3048)
			(end -0.120396 0.3048)
			(stroke
				(width 0.1)
				(type default)
			)
			(layer "B.Fab")
		)
		(fp_line
			(start -0.67945 -0.3048)
			(end -0.67945 0.3048)
			(stroke
				(width 0.1)
				(type default)
			)
			(layer "B.Fab")
		)
		(pad "1" smd circle
			(at 0.40005 0)
			(size 0 0)
			(layers "B.Cu" "B.Mask" "B.Paste")
			(net "GND")
		)
		(pad "2" smd circle
			(at -0.40005 0)
			(size 0 0)
			(layers "B.Cu" "B.Mask" "B.Paste")
			(net "FPGA_DEBUG_SW_SPARE")
		)
	)
	(footprint ""
		(layer "B.Cu")
		(at 232.537 -338.455 -90)
		(property "Reference" "R6765"
			(at 0 0 90)
			(layer "B.SilkS")
			(hide yes)
			(effects
				(font
					(size 1.27 1.27)
				)
				(justify mirror)
			)
		)
		(property "Value" ""
			(at 0 0 90)
			(layer "B.Fab")
			(effects
				(font
					(size 1.27 1.27)
				)
				(justify mirror)
			)
		)
		(duplicate_pad_numbers_are_jumpers no)
		(fp_line
			(start -0.32512 0.175006)
			(end 0.32512 0.175006)
			(stroke
				(width 0.1)
				(type default)
			)
			(layer "B.Fab")
		)
		(fp_line
			(start 0.32512 0.175006)
			(end 0.32512 -0.175006)
			(stroke
				(width 0.1)
				(type default)
			)
			(layer "B.Fab")
		)
		(fp_line
			(start -0.32512 -0.175006)
			(end -0.32512 0.175006)
			(stroke
				(width 0.1)
				(type default)
			)
			(layer "B.Fab")
		)
		(fp_line
			(start 0.32512 -0.175006)
			(end -0.32512 -0.175006)
			(stroke
				(width 0.1)
				(type default)
			)
			(layer "B.Fab")
		)
		(pad "1" smd rect
			(at 0.2667 0 90)
			(size 0.3048 0.381)
			(layers "B.Cu" "B.Mask" "B.Paste")
			(net "P1V8_CPU0_RT_1D")
		)
		(pad "2" smd rect
			(at -0.2667 0 270)
			(size 0.3048 0.381)
			(layers "B.Cu" "B.Mask" "B.Paste")
			(net "SMB_RT_CPU0_P1_R_SCL")
		)
	)
	(footprint ""
		(layer "B.Cu")
		(at 61.967872 -381.11303)
		(property "Reference" "C7020"
			(at 2.02692 3.319272 0)
			(unlocked yes)
			(layer "B.SilkS")
			(effects
				(font
					(size 0.7874 0.5842)
					(thickness 0.1524)
				)
				(justify left mirror)
			)
		)
		(property "Value" ""
			(at 0 0 0)
			(layer "B.Fab")
			(effects
				(font
					(size 1.27 1.27)
				)
				(justify mirror)
			)
		)
		(duplicate_pad_numbers_are_jumpers no)
		(fp_line
			(start -4.53898 -2.15011)
			(end -4.53898 2.15011)
			(stroke
				(width 0.1524)
				(type default)
			)
			(layer "B.SilkS")
		)
		(fp_line
			(start -4.53898 2.15011)
			(end 4.53898 2.15011)
			(stroke
				(width 0.1524)
				(type default)
			)
			(layer "B.SilkS")
		)
		(fp_line
			(start 4.53898 -2.150618)
			(end 4.539742 2.152142)
			(stroke
				(width 0.1524)
				(type default)
			)
			(layer "B.SilkS")
		)
		(fp_line
			(start 4.53898 -2.15011)
			(end -4.53898 -2.15011)
			(stroke
				(width 0.1524)
				(type default)
			)
			(layer "B.SilkS")
		)
		(fp_line
			(start 4.53898 2.15011)
			(end 4.53898 -2.15011)
			(stroke
				(width 0.1524)
				(type default)
			)
			(layer "B.SilkS")
		)
		(fp_line
			(start 4.69138 -2.150618)
			(end 4.692396 2.161032)
			(stroke
				(width 0.1524)
				(type default)
			)
			(layer "B.SilkS")
		)
		(fp_line
			(start 4.83108 2.150364)
			(end 4.447794 2.149348)
			(stroke
				(width 0.1524)
				(type default)
			)
			(layer "B.SilkS")
		)
		(fp_line
			(start 4.84378 -2.150618)
			(end 4.53898 -2.150618)
			(stroke
				(width 0.1524)
				(type default)
			)
			(layer "B.SilkS")
		)
		(fp_line
			(start 4.84378 -2.150618)
			(end 4.842256 2.163064)
			(stroke
				(width 0.1524)
				(type default)
			)
			(layer "B.SilkS")
		)
		(fp_line
			(start -3.64998 -2.15011)
			(end -3.64998 2.15011)
			(stroke
				(width 0.1)
				(type default)
			)
			(layer "B.Fab")
		)
		(fp_line
			(start -3.64998 2.15011)
			(end 3.64998 2.15011)
			(stroke
				(width 0.1)
				(type default)
			)
			(layer "B.Fab")
		)
		(fp_line
			(start 3.64998 -2.15011)
			(end -3.64998 -2.15011)
			(stroke
				(width 0.1)
				(type default)
			)
			(layer "B.Fab")
		)
		(fp_line
			(start 3.64998 2.15011)
			(end 3.64998 -2.15011)
			(stroke
				(width 0.1)
				(type default)
			)
			(layer "B.Fab")
		)
		(fp_text user "-"
			(at -5.075174 2.326132 0)
			(unlocked yes)
			(layer "B.SilkS")
			(effects
				(font
					(size 1.905 1.4224)
					(thickness 0.1524)
				)
				(justify left mirror)
			)
		)
		(fp_text user "+"
			(at 4.302252 2.545842 0)
			(unlocked yes)
			(layer "B.SilkS")
			(effects
				(font
					(size 1.905 1.4224)
					(thickness 0.1524)
				)
				(justify left mirror)
			)
		)
		(fp_text user "-"
			(at -4.313174 -0.094488 0)
			(unlocked yes)
			(layer "B.Fab")
			(effects
				(font
					(size 1.905 1.4224)
					(thickness 0.1524)
				)
				(justify left mirror)
			)
		)
		(fp_text user "+"
			(at 6.214872 -0.337058 0)
			(unlocked yes)
			(layer "B.Fab")
			(effects
				(font
					(size 1.905 1.4224)
					(thickness 0.1524)
				)
				(justify left mirror)
			)
		)
		(pad "1" smd rect
			(at 3.199892 0 180)
			(size 2.413 2.8194)
			(layers "B.Cu" "B.Mask" "B.Paste")
			(net "P0V9_CPU1_RT0_2A")
		)
		(pad "2" smd rect
			(at -3.199892 0 180)
			(size 2.413 2.8194)
			(layers "B.Cu" "B.Mask" "B.Paste")
			(net "GND")
		)
	)
)
